(kicad_pcb
	(version 20260206)
	(generator "pcbnew")
	(generator_version "10.0")
	(general
		(thickness 1.6)
		(legacy_teardrops no)
	)
	(paper "A4")
	(title_block
		(title "03242023_DA0F0TMBIJ0_F0T_Motherboard_J_brd_V01_OCP.brd")
		(comment 1 "Grand Teton / footprints 3711-3715 of 6105")
	)
	(layers
		(0 "F.Cu" signal "TOP")
		(4 "In1.Cu" signal "GND")
		(6 "In2.Cu" signal "IN1")
		(8 "In3.Cu" signal "GND1")
		(10 "In4.Cu" signal "IN2")
		(12 "In5.Cu" signal "GND2")
		(14 "In6.Cu" signal "IN3")
		(16 "In7.Cu" signal "GND3")
		(18 "In8.Cu" signal "VCC")
		(20 "In9.Cu" signal "VCC1")
		(22 "In10.Cu" signal "GND4")
		(24 "In11.Cu" signal "IN4")
		(26 "In12.Cu" signal "GND5")
		(28 "In13.Cu" signal "IN5")
		(30 "In14.Cu" signal "GND6")
		(32 "In15.Cu" signal "IN6")
		(34 "In16.Cu" signal "GND7")
		(2 "B.Cu" signal "BOTTOM")
		(9 "F.Adhes" user "F.Adhesive")
		(11 "B.Adhes" user "B.Adhesive")
		(13 "F.Paste" user "Package Geometry/Pastemask Top")
		(15 "B.Paste" user "Package Geometry/Pastemask Bottom")
		(5 "F.SilkS" user "Ref Des/Silkscreen Top")
		(7 "B.SilkS" user "Ref Des/Silkscreen Bottom")
		(1 "F.Mask" user "Board Geometry/Soldermask Top")
		(3 "B.Mask" user "Board Geometry/Soldermask Bottom")
		(17 "Dwgs.User" user "User.Drawings")
		(19 "Cmts.User" user "User.Comments")
		(21 "Eco1.User" user "User.Eco1")
		(23 "Eco2.User" user "User.Eco2")
		(25 "Edge.Cuts" user "Board Geometry/Outline")
		(27 "Margin" user)
		(31 "F.CrtYd" user "Package Geometry/Place Bound Top")
		(29 "B.CrtYd" user "Package Geometry/Place Bound Bottom")
		(35 "F.Fab" user "Ref Des/Assembly Top")
		(33 "B.Fab" user "Ref Des/Assembly Bottom")
	)
	(footprint ""
		(layer "F.Cu")
		(at 162.563302 -23.38959)
		(property "Reference" "R4149"
			(at 0 0 0)
			(layer "F.SilkS")
			(hide yes)
			(effects
				(font
					(size 1.27 1.27)
				)
			)
		)
		(property "Value" ""
			(at 0 0 0)
			(layer "F.Fab")
			(effects
				(font
					(size 1.27 1.27)
				)
			)
		)
		(duplicate_pad_numbers_are_jumpers no)
		(fp_line
			(start -0.7874 -0.4064)
			(end 0.7874 -0.4064)
			(stroke
				(width 0.1524)
				(type default)
			)
			(layer "F.SilkS")
		)
		(fp_line
			(start -0.7874 0.4064)
			(end -0.7874 -0.4064)
			(stroke
				(width 0.1524)
				(type default)
			)
			(layer "F.SilkS")
		)
		(fp_line
			(start 0.7874 -0.4064)
			(end 0.7874 0.4064)
			(stroke
				(width 0.1524)
				(type default)
			)
			(layer "F.SilkS")
		)
		(fp_line
			(start 0.7874 0.4064)
			(end -0.7874 0.4064)
			(stroke
				(width 0.1524)
				(type default)
			)
			(layer "F.SilkS")
		)
		(fp_line
			(start -0.67945 -0.305054)
			(end -0.12065 -0.305054)
			(stroke
				(width 0.1)
				(type default)
			)
			(layer "F.Fab")
		)
		(fp_line
			(start -0.67945 0.3048)
			(end -0.67945 -0.305054)
			(stroke
				(width 0.1)
				(type default)
			)
			(layer "F.Fab")
		)
		(fp_line
			(start -0.12065 -0.305054)
			(end -0.12065 -0.2794)
			(stroke
				(width 0.1)
				(type default)
			)
			(layer "F.Fab")
		)
		(fp_line
			(start -0.12065 -0.2794)
			(end 0.12065 -0.2794)
			(stroke
				(width 0.1)
				(type default)
			)
			(layer "F.Fab")
		)
		(fp_line
			(start -0.12065 0.2794)
			(end -0.12065 0.3048)
			(stroke
				(width 0.1)
				(type default)
			)
			(layer "F.Fab")
		)
		(fp_line
			(start -0.12065 0.3048)
			(end -0.67945 0.3048)
			(stroke
				(width 0.1)
				(type default)
			)
			(layer "F.Fab")
		)
		(fp_line
			(start 0.120396 0.2794)
			(end -0.12065 0.2794)
			(stroke
				(width 0.1)
				(type default)
			)
			(layer "F.Fab")
		)
		(fp_line
			(start 0.120396 0.3048)
			(end 0.120396 0.2794)
			(stroke
				(width 0.1)
				(type default)
			)
			(layer "F.Fab")
		)
		(fp_line
			(start 0.12065 -0.3048)
			(end 0.67945 -0.3048)
			(stroke
				(width 0.1)
				(type default)
			)
			(layer "F.Fab")
		)
		(fp_line
			(start 0.12065 -0.2794)
			(end 0.12065 -0.3048)
			(stroke
				(width 0.1)
				(type default)
			)
			(layer "F.Fab")
		)
		(fp_line
			(start 0.67945 -0.3048)
			(end 0.67945 0.3048)
			(stroke
				(width 0.1)
				(type default)
			)
			(layer "F.Fab")
		)
		(fp_line
			(start 0.67945 0.3048)
			(end 0.120396 0.3048)
			(stroke
				(width 0.1)
				(type default)
			)
			(layer "F.Fab")
		)
		(pad "1" smd circle
			(at -0.40005 0)
			(size 0 0)
			(layers "F.Cu" "F.Mask" "F.Paste")
			(net "SMB_1_PLD_3V3AUX_SCL")
		)
		(pad "2" smd circle
			(at 0.40005 0)
			(size 0 0)
			(layers "F.Cu" "F.Mask" "F.Paste")
			(net "SMB_1_PLD_3V3AUX_SCL_R1")
		)
	)
	(footprint ""
		(layer "F.Cu")
		(at 62.47257 -37.307266 180)
		(property "Reference" "Q118"
			(at 0.51435 -2.215388 0)
			(unlocked yes)
			(layer "F.SilkS")
			(effects
				(font
					(size 0.7874 0.5842)
					(thickness 0.1524)
				)
				(justify left)
			)
		)
		(property "Value" ""
			(at 0 0 180)
			(layer "F.Fab")
			(effects
				(font
					(size 1.27 1.27)
				)
			)
		)
		(duplicate_pad_numbers_are_jumpers no)
		(fp_line
			(start 1.332738 1.100074)
			(end -1.332738 1.100074)
			(stroke
				(width 0.1524)
				(type default)
			)
			(layer "F.SilkS")
		)
		(fp_line
			(start 1.332738 -1.100074)
			(end 1.332738 1.100074)
			(stroke
				(width 0.1524)
				(type default)
			)
			(layer "F.SilkS")
		)
		(fp_line
			(start 0.4826 -1.100074)
			(end 1.332738 -1.100074)
			(stroke
				(width 0.1524)
				(type default)
			)
			(layer "F.SilkS")
		)
		(fp_line
			(start 0 -0.541274)
			(end 0.4826 -1.100074)
			(stroke
				(width 0.1524)
				(type default)
			)
			(layer "F.SilkS")
		)
		(fp_line
			(start -0.4826 -1.100074)
			(end 0 -0.541274)
			(stroke
				(width 0.1524)
				(type default)
			)
			(layer "F.SilkS")
		)
		(fp_line
			(start -1.332738 1.100074)
			(end -1.332738 -1.100074)
			(stroke
				(width 0.1524)
				(type default)
			)
			(layer "F.SilkS")
		)
		(fp_line
			(start -1.332738 -1.100074)
			(end -0.4826 -1.100074)
			(stroke
				(width 0.1524)
				(type default)
			)
			(layer "F.SilkS")
		)
		(fp_poly
			(pts
				(xy -2.7432 -1.011174) (xy -2.041144 -0.660146) (xy -2.7432 -0.309118)
			)
			(stroke
				(width 0)
				(type default)
			)
			(fill yes)
			(layer "F.SilkS")
		)
		(fp_line
			(start 0.674878 1.100074)
			(end -0.674878 1.100074)
			(stroke
				(width 0.1)
				(type default)
			)
			(layer "F.Fab")
		)
		(fp_line
			(start 0.674878 -1.100074)
			(end 0.674878 1.100074)
			(stroke
				(width 0.1)
				(type default)
			)
			(layer "F.Fab")
		)
		(fp_line
			(start -0.674878 1.100074)
			(end -0.674878 -1.100074)
			(stroke
				(width 0.1)
				(type default)
			)
			(layer "F.Fab")
		)
		(fp_line
			(start -0.674878 -1.100074)
			(end 0.674878 -1.100074)
			(stroke
				(width 0.1)
				(type default)
			)
			(layer "F.Fab")
		)
		(fp_poly
			(pts
				(xy -2.2352 -0.298958) (xy -2.2352 -1.001014) (xy -1.533144 -0.649986)
			)
			(stroke
				(width 0)
				(type default)
			)
			(fill yes)
			(layer "F.Fab")
		)
		(pad "1" smd rect
			(at -0.94996 -0.649986 270)
			(size 0.4318 0.508)
			(layers "F.Cu" "F.Mask" "F.Paste")
			(net "GND")
		)
		(pad "2" smd rect
			(at -0.94996 0 270)
			(size 0.4318 0.508)
			(layers "F.Cu" "F.Mask" "F.Paste")
			(net "P12V_OCP_EN_2_R")
		)
		(pad "3" smd rect
			(at -0.94996 0.649986 270)
			(size 0.4318 0.508)
			(layers "F.Cu" "F.Mask" "F.Paste")
			(net "P12V_OCP_UV_2_R")
		)
		(pad "4" smd rect
			(at 0.94996 0.649986 270)
			(size 0.4318 0.508)
			(layers "F.Cu" "F.Mask" "F.Paste")
			(net "GND")
		)
		(pad "5" smd rect
			(at 0.94996 0 270)
			(size 0.4318 0.508)
			(layers "F.Cu" "F.Mask" "F.Paste")
			(net "P12V_OCP_2_EN_G")
		)
		(pad "6" smd rect
			(at 0.94996 -0.649986 270)
			(size 0.4318 0.508)
			(layers "F.Cu" "F.Mask" "F.Paste")
			(net "P12V_OCP_2_EN_G")
		)
	)
	(footprint ""
		(layer "F.Cu")
		(at 303.780444 -438.109106 -90)
		(property "Reference" "R4137"
			(at 0 0 270)
			(layer "F.SilkS")
			(hide yes)
			(effects
				(font
					(size 1.27 1.27)
				)
			)
		)
		(property "Value" ""
			(at 0 0 270)
			(layer "F.Fab")
			(effects
				(font
					(size 1.27 1.27)
				)
			)
		)
		(duplicate_pad_numbers_are_jumpers no)
		(fp_line
			(start -0.7874 0.4064)
			(end -0.7874 -0.4064)
			(stroke
				(width 0.1524)
				(type default)
			)
			(layer "F.SilkS")
		)
		(fp_line
			(start 0.7874 0.4064)
			(end -0.7874 0.4064)
			(stroke
				(width 0.1524)
				(type default)
			)
			(layer "F.SilkS")
		)
		(fp_line
			(start -0.7874 -0.4064)
			(end 0.7874 -0.4064)
			(stroke
				(width 0.1524)
				(type default)
			)
			(layer "F.SilkS")
		)
		(fp_line
			(start 0.7874 -0.4064)
			(end 0.7874 0.4064)
			(stroke
				(width 0.1524)
				(type default)
			)
			(layer "F.SilkS")
		)
		(fp_line
			(start -0.67945 0.3048)
			(end -0.67945 -0.305054)
			(stroke
				(width 0.1)
				(type default)
			)
			(layer "F.Fab")
		)
		(fp_line
			(start -0.12065 0.3048)
			(end -0.67945 0.3048)
			(stroke
				(width 0.1)
				(type default)
			)
			(layer "F.Fab")
		)
		(fp_line
			(start 0.120396 0.3048)
			(end 0.120396 0.2794)
			(stroke
				(width 0.1)
				(type default)
			)
			(layer "F.Fab")
		)
		(fp_line
			(start 0.67945 0.3048)
			(end 0.120396 0.3048)
			(stroke
				(width 0.1)
				(type default)
			)
			(layer "F.Fab")
		)
		(fp_line
			(start -0.12065 0.2794)
			(end -0.12065 0.3048)
			(stroke
				(width 0.1)
				(type default)
			)
			(layer "F.Fab")
		)
		(fp_line
			(start 0.120396 0.2794)
			(end -0.12065 0.2794)
			(stroke
				(width 0.1)
				(type default)
			)
			(layer "F.Fab")
		)
		(fp_line
			(start -0.12065 -0.2794)
			(end 0.12065 -0.2794)
			(stroke
				(width 0.1)
				(type default)
			)
			(layer "F.Fab")
		)
		(fp_line
			(start 0.12065 -0.2794)
			(end 0.12065 -0.3048)
			(stroke
				(width 0.1)
				(type default)
			)
			(layer "F.Fab")
		)
		(fp_line
			(start 0.12065 -0.3048)
			(end 0.67945 -0.3048)
			(stroke
				(width 0.1)
				(type default)
			)
			(layer "F.Fab")
		)
		(fp_line
			(start 0.67945 -0.3048)
			(end 0.67945 0.3048)
			(stroke
				(width 0.1)
				(type default)
			)
			(layer "F.Fab")
		)
		(fp_line
			(start -0.67945 -0.305054)
			(end -0.12065 -0.305054)
			(stroke
				(width 0.1)
				(type default)
			)
			(layer "F.Fab")
		)
		(fp_line
			(start -0.12065 -0.305054)
			(end -0.12065 -0.2794)
			(stroke
				(width 0.1)
				(type default)
			)
			(layer "F.Fab")
		)
		(pad "1" smd circle
			(at -0.40005 0 270)
			(size 0 0)
			(layers "F.Cu" "F.Mask" "F.Paste")
			(net "P3V3_AUX")
		)
		(pad "2" smd circle
			(at 0.40005 0 270)
			(size 0 0)
			(layers "F.Cu" "F.Mask" "F.Paste")
			(net "GPU_3V3IO_RSVD3_FFU_N")
		)
	)
	(footprint ""
		(layer "F.Cu")
		(at 113.16208 -395.207998 -90)
		(property "Reference" "Q74"
			(at 0.98806 -4.43484 0)
			(unlocked yes)
			(layer "F.SilkS")
			(effects
				(font
					(size 0.7874 0.5842)
					(thickness 0.1524)
				)
				(justify left)
			)
		)
		(property "Value" ""
			(at 0 0 270)
			(layer "F.Fab")
			(effects
				(font
					(size 1.27 1.27)
				)
			)
		)
		(duplicate_pad_numbers_are_jumpers no)
		(fp_line
			(start -1.332738 1.100074)
			(end -1.332738 -1.100074)
			(stroke
				(width 0.1524)
				(type default)
			)
			(layer "F.SilkS")
		)
		(fp_line
			(start 1.332738 1.100074)
			(end -1.332738 1.100074)
			(stroke
				(width 0.1524)
				(type default)
			)
			(layer "F.SilkS")
		)
		(fp_line
			(start 0 -0.541274)
			(end 0.4826 -1.100074)
			(stroke
				(width 0.1524)
				(type default)
			)
			(layer "F.SilkS")
		)
		(fp_line
			(start -1.332738 -1.100074)
			(end -0.4826 -1.100074)
			(stroke
				(width 0.1524)
				(type default)
			)
			(layer "F.SilkS")
		)
		(fp_line
			(start -0.4826 -1.100074)
			(end 0 -0.541274)
			(stroke
				(width 0.1524)
				(type default)
			)
			(layer "F.SilkS")
		)
		(fp_line
			(start 0.4826 -1.100074)
			(end 1.332738 -1.100074)
			(stroke
				(width 0.1524)
				(type default)
			)
			(layer "F.SilkS")
		)
		(fp_line
			(start 1.332738 -1.100074)
			(end 1.332738 1.100074)
			(stroke
				(width 0.1524)
				(type default)
			)
			(layer "F.SilkS")
		)
		(fp_poly
			(pts
				(xy -0.661416 -2.06121) (xy -1.012444 -1.359154) (xy -1.363472 -2.06121)
			)
			(stroke
				(width 0)
				(type default)
			)
			(fill yes)
			(layer "F.SilkS")
		)
		(fp_line
			(start -0.674878 1.100074)
			(end -0.674878 -1.100074)
			(stroke
				(width 0.1)
				(type default)
			)
			(layer "F.Fab")
		)
		(fp_line
			(start 0.674878 1.100074)
			(end -0.674878 1.100074)
			(stroke
				(width 0.1)
				(type default)
			)
			(layer "F.Fab")
		)
		(fp_line
			(start -0.674878 -1.100074)
			(end 0.674878 -1.100074)
			(stroke
				(width 0.1)
				(type default)
			)
			(layer "F.Fab")
		)
		(fp_line
			(start 0.674878 -1.100074)
			(end 0.674878 1.100074)
			(stroke
				(width 0.1)
				(type default)
			)
			(layer "F.Fab")
		)
		(fp_poly
			(pts
				(xy -2.2352 -0.298958) (xy -2.2352 -1.001014) (xy -1.533144 -0.649986)
			)
			(stroke
				(width 0)
				(type default)
			)
			(fill yes)
			(layer "F.Fab")
		)
		(pad "1" smd rect
			(at -0.94996 -0.649986)
			(size 0.4318 0.508)
			(layers "F.Cu" "F.Mask" "F.Paste")
			(net "GND")
		)
		(pad "2" smd rect
			(at -0.94996 0)
			(size 0.4318 0.508)
			(layers "F.Cu" "F.Mask" "F.Paste")
			(net "FM_SMB_2_ALERT_GPU_N")
		)
		(pad "3" smd rect
			(at -0.94996 0.649986)
			(size 0.4318 0.508)
			(layers "F.Cu" "F.Mask" "F.Paste")
			(net "FM_SMB_2_ALERT_GPU_ISO_N")
		)
		(pad "4" smd rect
			(at 0.94996 0.649986)
			(size 0.4318 0.508)
			(layers "F.Cu" "F.Mask" "F.Paste")
			(net "GND")
		)
		(pad "5" smd rect
			(at 0.94996 0)
			(size 0.4318 0.508)
			(layers "F.Cu" "F.Mask" "F.Paste")
			(net "FM_SMB_2_ALERT_GPU")
		)
		(pad "6" smd rect
			(at 0.94996 -0.649986)
			(size 0.4318 0.508)
			(layers "F.Cu" "F.Mask" "F.Paste")
			(net "FM_SMB_2_ALERT_GPU")
		)
	)
	(footprint ""
		(layer "F.Cu")
		(at 121.52884 -366.796066 -90)
		(property "Reference" "PC1267"
			(at 0 0 270)
			(layer "F.SilkS")
			(hide yes)
			(effects
				(font
					(size 1.27 1.27)
				)
			)
		)
		(property "Value" ""
			(at 0 0 270)
			(layer "F.Fab")
			(effects
				(font
					(size 1.27 1.27)
				)
			)
		)
		(duplicate_pad_numbers_are_jumpers no)
		(fp_line
			(start -0.7874 0.4064)
			(end -0.7874 -0.4064)
			(stroke
				(width 0.1524)
				(type default)
			)
			(layer "F.SilkS")
		)
		(fp_line
			(start 0.7874 0.4064)
			(end -0.7874 0.4064)
			(stroke
				(width 0.1524)
				(type default)
			)
			(layer "F.SilkS")
		)
		(fp_line
			(start -0.7874 -0.4064)
			(end 0.7874 -0.4064)
			(stroke
				(width 0.1524)
				(type default)
			)
			(layer "F.SilkS")
		)
		(fp_line
			(start 0.7874 -0.4064)
			(end 0.7874 0.4064)
			(stroke
				(width 0.1524)
				(type default)
			)
			(layer "F.SilkS")
		)
		(fp_line
			(start -0.67945 0.3048)
			(end -0.67945 -0.305054)
			(stroke
				(width 0.1)
				(type default)
			)
			(layer "F.Fab")
		)
		(fp_line
			(start -0.12065 0.3048)
			(end -0.67945 0.3048)
			(stroke
				(width 0.1)
				(type default)
			)
			(layer "F.Fab")
		)
		(fp_line
			(start 0.120396 0.3048)
			(end 0.120396 0.2794)
			(stroke
				(width 0.1)
				(type default)
			)
			(layer "F.Fab")
		)
		(fp_line
			(start 0.67945 0.3048)
			(end 0.120396 0.3048)
			(stroke
				(width 0.1)
				(type default)
			)
			(layer "F.Fab")
		)
		(fp_line
			(start -0.12065 0.2794)
			(end -0.12065 0.3048)
			(stroke
				(width 0.1)
				(type default)
			)
			(layer "F.Fab")
		)
		(fp_line
			(start 0.120396 0.2794)
			(end -0.12065 0.2794)
			(stroke
				(width 0.1)
				(type default)
			)
			(layer "F.Fab")
		)
		(fp_line
			(start -0.12065 -0.2794)
			(end 0.12065 -0.2794)
			(stroke
				(width 0.1)
				(type default)
			)
			(layer "F.Fab")
		)
		(fp_line
			(start 0.12065 -0.2794)
			(end 0.12065 -0.3048)
			(stroke
				(width 0.1)
				(type default)
			)
			(layer "F.Fab")
		)
		(fp_line
			(start 0.12065 -0.3048)
			(end 0.67945 -0.3048)
			(stroke
				(width 0.1)
				(type default)
			)
			(layer "F.Fab")
		)
		(fp_line
			(start 0.67945 -0.3048)
			(end 0.67945 0.3048)
			(stroke
				(width 0.1)
				(type default)
			)
			(layer "F.Fab")
		)
		(fp_line
			(start -0.67945 -0.305054)
			(end -0.12065 -0.305054)
			(stroke
				(width 0.1)
				(type default)
			)
			(layer "F.Fab")
		)
		(fp_line
			(start -0.12065 -0.305054)
			(end -0.12065 -0.2794)
			(stroke
				(width 0.1)
				(type default)
			)
			(layer "F.Fab")
		)
		(pad "1" smd circle
			(at -0.40005 0 270)
			(size 0 0)
			(layers "F.Cu" "F.Mask" "F.Paste")
			(net "PVPP_HBM_CPU1")
		)
		(pad "2" smd circle
			(at 0.40005 0 270)
			(size 0 0)
			(layers "F.Cu" "F.Mask" "F.Paste")
			(net "GND")
		)
	)
)
